# T6G (Grand Teton) — schematic netlist excerpt (pin names and nets, part order shuffled) for the footprints in the layout excerpt that follows; sources: Cadence DE-HDL packaged netlist, KiCad conversion of 04192023_DAF0TMB3IC0_F0TG_MB_C_brd_V02_OCP.brd

R413  Q_RES  2.2K 5% CHIP  pkg 0402LF  page 27 : A = CPU0_XTRIG_L4 ; B = PVDD18_S5_P0
R1685  Q_RES  10 1% CHIP  pkg 0402LF  page 96 : A = I3C_SPD_DDRGL_CPU0_SDA ; B = I3C_SPD_DDRK_CPU0_SDA

(kicad_pcb
	(version 20260206)
	(generator "pcbnew")
	(generator_version "10.0")
	(general
		(thickness 1.6)
		(legacy_teardrops no)
	)
	(paper "A4")
	(title_block
		(title "04192023_DAF0TMB3IC0_F0TG_MB_C_brd_V02_OCP.brd")
		(comment 1 "Grand Teton / footprints 6196-6197 of 8354")
	)
	(layers
		(0 "F.Cu" signal "TOP")
		(4 "In1.Cu" signal "GND")
		(6 "In2.Cu" signal "IN1")
		(8 "In3.Cu" signal "GND1")
		(10 "In4.Cu" signal "IN2")
		(12 "In5.Cu" signal "GND2")
		(14 "In6.Cu" signal "IN3")
		(16 "In7.Cu" signal "GND3")
		(18 "In8.Cu" signal "VCC")
		(20 "In9.Cu" signal "VCC1")
		(22 "In10.Cu" signal "GND4")
		(24 "In11.Cu" signal "IN4")
		(26 "In12.Cu" signal "GND5")
		(28 "In13.Cu" signal "IN5")
		(30 "In14.Cu" signal "GND6")
		(32 "In15.Cu" signal "IN6")
		(34 "In16.Cu" signal "GND7")
		(2 "B.Cu" signal "BOTTOM")
		(9 "F.Adhes" user "F.Adhesive")
		(11 "B.Adhes" user "B.Adhesive")
		(13 "F.Paste" user "Package Geometry/Pastemask Top")
		(15 "B.Paste" user "Package Geometry/Pastemask Bottom")
		(5 "F.SilkS" user "Ref Des/Silkscreen Top")
		(7 "B.SilkS" user "Ref Des/Silkscreen Bottom")
		(1 "F.Mask" user "Board Geometry/Soldermask Top")
		(3 "B.Mask" user "Board Geometry/Soldermask Bottom")
		(17 "Dwgs.User" user "User.Drawings")
		(19 "Cmts.User" user "User.Comments")
		(21 "Eco1.User" user "User.Eco1")
		(23 "Eco2.User" user "User.Eco2")
		(25 "Edge.Cuts" user "Board Geometry/Outline")
		(27 "Margin" user)
		(31 "F.CrtYd" user "Package Geometry/Place Bound Top")
		(29 "B.CrtYd" user "Package Geometry/Place Bound Bottom")
		(35 "F.Fab" user "Ref Des/Assembly Top")
		(33 "B.Fab" user "Ref Des/Assembly Bottom")
	)
	(footprint ""
		(layer "B.Cu")
		(at 445.888364 -195.86067 180)
		(property "Reference" "R1685"
			(at 0 0 0)
			(layer "B.SilkS")
			(hide yes)
			(effects
				(font
					(size 1.27 1.27)
				)
				(justify mirror)
			)
		)
		(property "Value" ""
			(at 0 0 0)
			(layer "B.Fab")
			(effects
				(font
					(size 1.27 1.27)
				)
				(justify mirror)
			)
		)
		(duplicate_pad_numbers_are_jumpers no)
		(fp_line
			(start 0.7874 0.4064)
			(end 0.7874 -0.4064)
			(stroke
				(width 0.1524)
				(type default)
			)
			(layer "B.SilkS")
		)
		(fp_line
			(start 0.7874 -0.4064)
			(end -0.7874 -0.4064)
			(stroke
				(width 0.1524)
				(type default)
			)
			(layer "B.SilkS")
		)
		(fp_line
			(start -0.7874 0.4064)
			(end 0.7874 0.4064)
			(stroke
				(width 0.1524)
				(type default)
			)
			(layer "B.SilkS")
		)
		(fp_line
			(start -0.7874 -0.4064)
			(end -0.7874 0.4064)
			(stroke
				(width 0.1524)
				(type default)
			)
			(layer "B.SilkS")
		)
		(fp_line
			(start 0.67945 0.3048)
			(end 0.67945 -0.305054)
			(stroke
				(width 0.1)
				(type default)
			)
			(layer "B.Fab")
		)
		(fp_line
			(start 0.67945 -0.305054)
			(end 0.12065 -0.305054)
			(stroke
				(width 0.1)
				(type default)
			)
			(layer "B.Fab")
		)
		(fp_line
			(start 0.12065 0.3048)
			(end 0.67945 0.3048)
			(stroke
				(width 0.1)
				(type default)
			)
			(layer "B.Fab")
		)
		(fp_line
			(start 0.12065 0.2794)
			(end 0.12065 0.3048)
			(stroke
				(width 0.1)
				(type default)
			)
			(layer "B.Fab")
		)
		(fp_line
			(start 0.12065 -0.2794)
			(end -0.12065 -0.2794)
			(stroke
				(width 0.1)
				(type default)
			)
			(layer "B.Fab")
		)
		(fp_line
			(start 0.12065 -0.305054)
			(end 0.12065 -0.2794)
			(stroke
				(width 0.1)
				(type default)
			)
			(layer "B.Fab")
		)
		(fp_line
			(start -0.120396 0.3048)
			(end -0.120396 0.2794)
			(stroke
				(width 0.1)
				(type default)
			)
			(layer "B.Fab")
		)
		(fp_line
			(start -0.120396 0.2794)
			(end 0.12065 0.2794)
			(stroke
				(width 0.1)
				(type default)
			)
			(layer "B.Fab")
		)
		(fp_line
			(start -0.12065 -0.2794)
			(end -0.12065 -0.3048)
			(stroke
				(width 0.1)
				(type default)
			)
			(layer "B.Fab")
		)
		(fp_line
			(start -0.12065 -0.3048)
			(end -0.67945 -0.3048)
			(stroke
				(width 0.1)
				(type default)
			)
			(layer "B.Fab")
		)
		(fp_line
			(start -0.67945 0.3048)
			(end -0.120396 0.3048)
			(stroke
				(width 0.1)
				(type default)
			)
			(layer "B.Fab")
		)
		(fp_line
			(start -0.67945 -0.3048)
			(end -0.67945 0.3048)
			(stroke
				(width 0.1)
				(type default)
			)
			(layer "B.Fab")
		)
		(pad "1" smd circle
			(at 0.40005 0)
			(size 0 0)
			(layers "B.Cu" "B.Mask" "B.Paste")
			(net "I3C_SPD_DDRGL_CPU0_SDA")
		)
		(pad "2" smd circle
			(at -0.40005 0)
			(size 0 0)
			(layers "B.Cu" "B.Mask" "B.Paste")
			(net "I3C_SPD_DDRK_CPU0_SDA")
		)
	)
	(footprint ""
		(layer "B.Cu")
		(at 325.799958 -202.113896 90)
		(property "Reference" "R413"
			(at 0 0 90)
			(layer "B.SilkS")
			(hide yes)
			(effects
				(font
					(size 1.27 1.27)
				)
				(justify mirror)
			)
		)
		(property "Value" ""
			(at 0 0 90)
			(layer "B.Fab")
			(effects
				(font
					(size 1.27 1.27)
				)
				(justify mirror)
			)
		)
		(duplicate_pad_numbers_are_jumpers no)
		(fp_line
			(start 0.7874 -0.4064)
			(end -0.7874 -0.4064)
			(stroke
				(width 0.1524)
				(type default)
			)
			(layer "B.SilkS")
		)
		(fp_line
			(start -0.7874 -0.4064)
			(end -0.7874 0.4064)
			(stroke
				(width 0.1524)
				(type default)
			)
			(layer "B.SilkS")
		)
		(fp_line
			(start 0.7874 0.4064)
			(end 0.7874 -0.4064)
			(stroke
				(width 0.1524)
				(type default)
			)
			(layer "B.SilkS")
		)
		(fp_line
			(start -0.7874 0.4064)
			(end 0.7874 0.4064)
			(stroke
				(width 0.1524)
				(type default)
			)
			(layer "B.SilkS")
		)
		(fp_line
			(start 0.67945 -0.305054)
			(end 0.12065 -0.305054)
			(stroke
				(width 0.1)
				(type default)
			)
			(layer "B.Fab")
		)
		(fp_line
			(start 0.12065 -0.305054)
			(end 0.12065 -0.2794)
			(stroke
				(width 0.1)
				(type default)
			)
			(layer "B.Fab")
		)
		(fp_line
			(start -0.12065 -0.3048)
			(end -0.67945 -0.3048)
			(stroke
				(width 0.1)
				(type default)
			)
			(layer "B.Fab")
		)
		(fp_line
			(start -0.67945 -0.3048)
			(end -0.67945 0.3048)
			(stroke
				(width 0.1)
				(type default)
			)
			(layer "B.Fab")
		)
		(fp_line
			(start 0.12065 -0.2794)
			(end -0.12065 -0.2794)
			(stroke
				(width 0.1)
				(type default)
			)
			(layer "B.Fab")
		)
		(fp_line
			(start -0.12065 -0.2794)
			(end -0.12065 -0.3048)
			(stroke
				(width 0.1)
				(type default)
			)
			(layer "B.Fab")
		)
		(fp_line
			(start 0.12065 0.2794)
			(end 0.12065 0.3048)
			(stroke
				(width 0.1)
				(type default)
			)
			(layer "B.Fab")
		)
		(fp_line
			(start -0.120396 0.2794)
			(end 0.12065 0.2794)
			(stroke
				(width 0.1)
				(type default)
			)
			(layer "B.Fab")
		)
		(fp_line
			(start 0.67945 0.3048)
			(end 0.67945 -0.305054)
			(stroke
				(width 0.1)
				(type default)
			)
			(layer "B.Fab")
		)
		(fp_line
			(start 0.12065 0.3048)
			(end 0.67945 0.3048)
			(stroke
				(width 0.1)
				(type default)
			)
			(layer "B.Fab")
		)
		(fp_line
			(start -0.120396 0.3048)
			(end -0.120396 0.2794)
			(stroke
				(width 0.1)
				(type default)
			)
			(layer "B.Fab")
		)
		(fp_line
			(start -0.67945 0.3048)
			(end -0.120396 0.3048)
			(stroke
				(width 0.1)
				(type default)
			)
			(layer "B.Fab")
		)
		(pad "1" smd circle
			(at 0.40005 0 270)
			(size 0 0)
			(layers "B.Cu" "B.Mask" "B.Paste")
			(net "CPU0_XTRIG_L4")
		)
		(pad "2" smd circle
			(at -0.40005 0 270)
			(size 0 0)
			(layers "B.Cu" "B.Mask" "B.Paste")
			(net "PVDD18_S5_P0")
		)
	)
)
